(kicad_pcb
	(version 20241229)
	(generator "pcbnew")
	(generator_version "9.0")
	(general
		(thickness 1.61)
		(legacy_teardrops no)
	)
	(paper "A3")
	(title_block
		(title "SO-DIMM DDR5 Tester")
		(date "2025-11-26")
		(rev "1.3.0")
		(comment 9 "footprints 338-343 of 627")
	)
	(layers
		(0 "F.Cu" signal)
		(4 "In1.Cu" power)
		(6 "In2.Cu" mixed)
		(8 "In3.Cu" power)
		(10 "In4.Cu" mixed)
		(12 "In5.Cu" power)
		(14 "In6.Cu" mixed)
		(16 "In7.Cu" power)
		(18 "In8.Cu" power)
		(20 "In9.Cu" mixed)
		(22 "In10.Cu" power)
		(2 "B.Cu" signal)
		(9 "F.Adhes" user "F.Adhesive")
		(11 "B.Adhes" user "B.Adhesive")
		(13 "F.Paste" user)
		(15 "B.Paste" user)
		(5 "F.SilkS" user "F.Silkscreen")
		(7 "B.SilkS" user "B.Silkscreen")
		(1 "F.Mask" user)
		(3 "B.Mask" user)
		(17 "Dwgs.User" user "User.Drawings")
		(19 "Cmts.User" user "User.Comments")
		(21 "Eco1.User" user "User.Eco1")
		(23 "Eco2.User" user "User.Eco2")
		(25 "Edge.Cuts" user)
		(27 "Margin" user)
		(31 "F.CrtYd" user "F.Courtyard")
		(29 "B.CrtYd" user "B.Courtyard")
		(35 "F.Fab" user)
		(33 "B.Fab" user)
	)
	(footprint "antmicro-footprints:R_0402_1005Metric"
		(layer "B.Cu")
		(at 85.200501 152.813149 180)
		(descr "Resistor SMD 0402")
		(tags "resistor SMD 0402")
		(property "Reference" "R108"
			(at -1.122484 0.772697 0)
			(layer "B.SilkS")
			(hide yes)
			(effects
				(font
					(size 0.7 0.7)
					(thickness 0.15)
				)
				(justify left bottom mirror)
			)
		)
		(property "Value" "R_10k_0402"
			(at -1.011843 -1.772047 0)
			(layer "B.Fab")
			(effects
				(font
					(size 0.7 0.7)
					(thickness 0.15)
				)
				(justify left bottom mirror)
			)
		)
		(property "Datasheet" "https://www.bourns.com/docs/product-datasheets/cr.pdf"
			(at 0 0 180)
			(layer "F.Fab")
			(hide yes)
			(effects
				(font
					(size 1.27 1.27)
					(thickness 0.15)
				)
			)
		)
		(property "Author" "Antmicro"
			(at 170.401002 305.626298 0)
			(layer "B.Fab")
			(hide yes)
			(effects
				(font
					(size 1 1)
					(thickness 0.15)
				)
				(justify mirror)
			)
		)
		(property "License" "Apache-2.0"
			(at 170.401002 305.626298 0)
			(layer "B.Fab")
			(hide yes)
			(effects
				(font
					(size 1 1)
					(thickness 0.15)
				)
				(justify mirror)
			)
		)
		(property "MPN" "CR0402-FX-1002GLF"
			(at 170.401002 305.626298 0)
			(layer "B.Fab")
			(hide yes)
			(effects
				(font
					(size 1 1)
					(thickness 0.15)
				)
				(justify mirror)
			)
		)
		(property "Manufacturer" "Bourns"
			(at 170.401002 305.626298 0)
			(layer "B.Fab")
			(hide yes)
			(effects
				(font
					(size 1 1)
					(thickness 0.15)
				)
				(justify mirror)
			)
		)
		(property "Tolerance" "1%"
			(at 170.401002 305.626298 0)
			(layer "B.Fab")
			(hide yes)
			(effects
				(font
					(size 1 1)
					(thickness 0.15)
				)
				(justify mirror)
			)
		)
		(property "Val" "10k"
			(at 170.401002 305.626298 0)
			(layer "B.Fab")
			(hide yes)
			(effects
				(font
					(size 1 1)
					(thickness 0.15)
				)
				(justify mirror)
			)
		)
		(sheetname "/Ethernet/")
		(sheetfile "ethernet.kicad_sch")
		(attr smd)
		(fp_rect
			(start -0.93 0.47)
			(end 0.93 -0.47)
			(stroke
				(width 0.05)
				(type solid)
			)
			(fill no)
			(layer "B.CrtYd")
		)
		(fp_rect
			(start -0.5 0.25)
			(end 0.5 -0.25)
			(stroke
				(width 0.15)
				(type solid)
			)
			(fill no)
			(layer "B.Fab")
		)
		(pad "1" smd roundrect
			(at -0.485 0 180)
			(size 0.59 0.64)
			(layers "B.Cu" "B.Mask" "B.Paste")
			(roundrect_rratio 0.25)
			(net 602 "/Ethernet/LED_SPD")
			(pintype "passive")
		)
		(pad "2" smd roundrect
			(at 0.485 0 180)
			(size 0.59 0.64)
			(layers "B.Cu" "B.Mask" "B.Paste")
			(roundrect_rratio 0.25)
			(net 200 "+3V3")
			(pintype "passive")
		)
	)
	(footprint "antmicro-footprints:R_0402_1005Metric"
		(layer "B.Cu")
		(at 85.200501 154.313149 180)
		(descr "Resistor SMD 0402")
		(tags "resistor SMD 0402")
		(property "Reference" "R109"
			(at -1.122484 0.772697 0)
			(layer "B.SilkS")
			(hide yes)
			(effects
				(font
					(size 0.7 0.7)
					(thickness 0.15)
				)
				(justify left bottom mirror)
			)
		)
		(property "Value" "R_10k_0402"
			(at -1.011843 -1.772047 0)
			(layer "B.Fab")
			(effects
				(font
					(size 0.7 0.7)
					(thickness 0.15)
				)
				(justify left bottom mirror)
			)
		)
		(property "Datasheet" "https://www.bourns.com/docs/product-datasheets/cr.pdf"
			(at 0 0 180)
			(layer "F.Fab")
			(hide yes)
			(effects
				(font
					(size 1.27 1.27)
					(thickness 0.15)
				)
			)
		)
		(property "Author" "Antmicro"
			(at 170.401002 308.626298 0)
			(layer "B.Fab")
			(hide yes)
			(effects
				(font
					(size 1 1)
					(thickness 0.15)
				)
				(justify mirror)
			)
		)
		(property "License" "Apache-2.0"
			(at 170.401002 308.626298 0)
			(layer "B.Fab")
			(hide yes)
			(effects
				(font
					(size 1 1)
					(thickness 0.15)
				)
				(justify mirror)
			)
		)
		(property "MPN" "CR0402-FX-1002GLF"
			(at 170.401002 308.626298 0)
			(layer "B.Fab")
			(hide yes)
			(effects
				(font
					(size 1 1)
					(thickness 0.15)
				)
				(justify mirror)
			)
		)
		(property "Manufacturer" "Bourns"
			(at 170.401002 308.626298 0)
			(layer "B.Fab")
			(hide yes)
			(effects
				(font
					(size 1 1)
					(thickness 0.15)
				)
				(justify mirror)
			)
		)
		(property "Tolerance" "1%"
			(at 170.401002 308.626298 0)
			(layer "B.Fab")
			(hide yes)
			(effects
				(font
					(size 1 1)
					(thickness 0.15)
				)
				(justify mirror)
			)
		)
		(property "Val" "10k"
			(at 170.401002 308.626298 0)
			(layer "B.Fab")
			(hide yes)
			(effects
				(font
					(size 1 1)
					(thickness 0.15)
				)
				(justify mirror)
			)
		)
		(sheetname "/Ethernet/")
		(sheetfile "ethernet.kicad_sch")
		(attr smd)
		(fp_rect
			(start -0.93 0.47)
			(end 0.93 -0.47)
			(stroke
				(width 0.05)
				(type solid)
			)
			(fill no)
			(layer "B.CrtYd")
		)
		(fp_rect
			(start -0.5 0.25)
			(end 0.5 -0.25)
			(stroke
				(width 0.15)
				(type solid)
			)
			(fill no)
			(layer "B.Fab")
		)
		(pad "1" smd roundrect
			(at -0.485 0 180)
			(size 0.59 0.64)
			(layers "B.Cu" "B.Mask" "B.Paste")
			(roundrect_rratio 0.25)
			(net 603 "/Ethernet/LED_LINK")
			(pintype "passive")
		)
		(pad "2" smd roundrect
			(at 0.485 0 180)
			(size 0.59 0.64)
			(layers "B.Cu" "B.Mask" "B.Paste")
			(roundrect_rratio 0.25)
			(net 200 "+3V3")
			(pintype "passive")
		)
	)
	(footprint "antmicro-footprints:C_0402_1005Metric"
		(layer "B.Cu")
		(at 95.6 150.3 90)
		(descr "Capacitor SMD 0402")
		(tags "capacitor SMD 0402")
		(property "Reference" "C146"
			(at 0 0.699 270)
			(layer "B.SilkS")
			(hide yes)
			(effects
				(font
					(size 0.7 0.7)
					(thickness 0.15)
				)
				(justify left bottom mirror)
			)
		)
		(property "Value" "C_4u7_0402"
			(at -1.022927 -2.155213 270)
			(layer "B.Fab")
			(effects
				(font
					(size 0.7 0.7)
					(thickness 0.15)
				)
				(justify left bottom mirror)
			)
		)
		(property "Datasheet" "https://www.murata.com/products/productdetail?partno=GRM155R61A475MEAA%23"
			(at 0 0 90)
			(layer "F.Fab")
			(hide yes)
			(effects
				(font
					(size 1.27 1.27)
					(thickness 0.15)
				)
			)
		)
		(property "Author" "Antmicro"
			(at 245.9 54.7 0)
			(layer "B.Fab")
			(hide yes)
			(effects
				(font
					(size 1 1)
					(thickness 0.15)
				)
				(justify mirror)
			)
		)
		(property "Dielectric" ""
			(at 245.9 54.7 0)
			(layer "B.Fab")
			(hide yes)
			(effects
				(font
					(size 1 1)
					(thickness 0.15)
				)
				(justify mirror)
			)
		)
		(property "License" "Apache-2.0"
			(at 245.9 54.7 0)
			(layer "B.Fab")
			(hide yes)
			(effects
				(font
					(size 1 1)
					(thickness 0.15)
				)
				(justify mirror)
			)
		)
		(property "MPN" "GRM155R61A475MEAAD"
			(at 245.9 54.7 0)
			(layer "B.Fab")
			(hide yes)
			(effects
				(font
					(size 1 1)
					(thickness 0.15)
				)
				(justify mirror)
			)
		)
		(property "Manufacturer" "Murata"
			(at 245.9 54.7 0)
			(layer "B.Fab")
			(hide yes)
			(effects
				(font
					(size 1 1)
					(thickness 0.15)
				)
				(justify mirror)
			)
		)
		(property "Val" "4u7"
			(at 245.9 54.7 0)
			(layer "B.Fab")
			(hide yes)
			(effects
				(font
					(size 1 1)
					(thickness 0.15)
				)
				(justify mirror)
			)
		)
		(property "Voltage" ""
			(at 245.9 54.7 0)
			(layer "B.Fab")
			(hide yes)
			(effects
				(font
					(size 1 1)
					(thickness 0.15)
				)
				(justify mirror)
			)
		)
		(sheetname "/Ethernet/")
		(sheetfile "ethernet.kicad_sch")
		(attr smd)
		(fp_rect
			(start -0.9659 0.481258)
			(end 0.9649 -0.458742)
			(stroke
				(width 0.05)
				(type solid)
			)
			(fill no)
			(layer "B.CrtYd")
		)
		(fp_line
			(start 0.499 -0.248)
			(end -0.499 -0.248)
			(stroke
				(width 0.15)
				(type solid)
			)
			(layer "B.Fab")
		)
		(fp_line
			(start -0.499 -0.248)
			(end -0.499 0.25)
			(stroke
				(width 0.15)
				(type solid)
			)
			(layer "B.Fab")
		)
		(fp_line
			(start 0.499 0.25)
			(end 0.499 -0.248)
			(stroke
				(width 0.15)
				(type solid)
			)
			(layer "B.Fab")
		)
		(fp_line
			(start -0.499 0.25)
			(end 0.499 0.25)
			(stroke
				(width 0.15)
				(type solid)
			)
			(layer "B.Fab")
		)
		(pad "1" smd roundrect
			(at -0.484 0 90)
			(size 0.59 0.64)
			(layers "B.Cu" "B.Mask" "B.Paste")
			(roundrect_rratio 0.25)
			(net 132 "/Ethernet/AVDDL")
			(pintype "passive")
		)
		(pad "2" smd roundrect
			(at 0.484 0 90)
			(size 0.59 0.64)
			(layers "B.Cu" "B.Mask" "B.Paste")
			(roundrect_rratio 0.25)
			(net 1 "GND")
			(pintype "passive")
		)
	)
	(footprint "antmicro-footprints:C_0402_1005Metric"
		(layer "B.Cu")
		(at 93.308672 158.004992 90)
		(descr "Capacitor SMD 0402")
		(tags "capacitor SMD 0402")
		(property "Reference" "C145"
			(at 0 0.699 270)
			(layer "B.SilkS")
			(hide yes)
			(effects
				(font
					(size 0.7 0.7)
					(thickness 0.15)
				)
				(justify left bottom mirror)
			)
		)
		(property "Value" "C_470n_0402"
			(at -1.022927 -2.155213 270)
			(layer "B.Fab")
			(effects
				(font
					(size 0.7 0.7)
					(thickness 0.15)
				)
				(justify left bottom mirror)
			)
		)
		(property "Datasheet" "https://product.tdk.com/en/search/capacitor/ceramic/mlcc/info?part_no=C1005X5R1E474M050BB"
			(at 0 0 90)
			(layer "F.Fab")
			(hide yes)
			(effects
				(font
					(size 1.27 1.27)
					(thickness 0.15)
				)
			)
		)
		(property "Author" "Antmicro"
			(at 251.313664 64.69632 0)
			(layer "B.Fab")
			(hide yes)
			(effects
				(font
					(size 1 1)
					(thickness 0.15)
				)
				(justify mirror)
			)
		)
		(property "Dielectric" ""
			(at 251.313664 64.69632 0)
			(layer "B.Fab")
			(hide yes)
			(effects
				(font
					(size 1 1)
					(thickness 0.15)
				)
				(justify mirror)
			)
		)
		(property "License" "Apache-2.0"
			(at 251.313664 64.69632 0)
			(layer "B.Fab")
			(hide yes)
			(effects
				(font
					(size 1 1)
					(thickness 0.15)
				)
				(justify mirror)
			)
		)
		(property "MPN" "C1005X5R1E474M050BB"
			(at 251.313664 64.69632 0)
			(layer "B.Fab")
			(hide yes)
			(effects
				(font
					(size 1 1)
					(thickness 0.15)
				)
				(justify mirror)
			)
		)
		(property "Manufacturer" "TDK"
			(at 251.313664 64.69632 0)
			(layer "B.Fab")
			(hide yes)
			(effects
				(font
					(size 1 1)
					(thickness 0.15)
				)
				(justify mirror)
			)
		)
		(property "Val" "470n"
			(at 251.313664 64.69632 0)
			(layer "B.Fab")
			(hide yes)
			(effects
				(font
					(size 1 1)
					(thickness 0.15)
				)
				(justify mirror)
			)
		)
		(property "Voltage" ""
			(at 251.313664 64.69632 0)
			(layer "B.Fab")
			(hide yes)
			(effects
				(font
					(size 1 1)
					(thickness 0.15)
				)
				(justify mirror)
			)
		)
		(sheetname "/Ethernet/")
		(sheetfile "ethernet.kicad_sch")
		(attr smd)
		(fp_rect
			(start -0.9659 0.481258)
			(end 0.9649 -0.458742)
			(stroke
				(width 0.05)
				(type solid)
			)
			(fill no)
			(layer "B.CrtYd")
		)
		(fp_line
			(start 0.499 -0.248)
			(end -0.499 -0.248)
			(stroke
				(width 0.15)
				(type solid)
			)
			(layer "B.Fab")
		)
		(fp_line
			(start -0.499 -0.248)
			(end -0.499 0.25)
			(stroke
				(width 0.15)
				(type solid)
			)
			(layer "B.Fab")
		)
		(fp_line
			(start 0.499 0.25)
			(end 0.499 -0.248)
			(stroke
				(width 0.15)
				(type solid)
			)
			(layer "B.Fab")
		)
		(fp_line
			(start -0.499 0.25)
			(end 0.499 0.25)
			(stroke
				(width 0.15)
				(type solid)
			)
			(layer "B.Fab")
		)
		(pad "1" smd roundrect
			(at -0.484 0 90)
			(size 0.59 0.64)
			(layers "B.Cu" "B.Mask" "B.Paste")
			(roundrect_rratio 0.25)
			(net 199 "+1V2")
			(pintype "passive")
		)
		(pad "2" smd roundrect
			(at 0.484 0 90)
			(size 0.59 0.64)
			(layers "B.Cu" "B.Mask" "B.Paste")
			(roundrect_rratio 0.25)
			(net 1 "GND")
			(pintype "passive")
		)
	)
	(footprint "antmicro-footprints:C_0402_1005Metric"
		(layer "B.Cu")
		(at 95.308672 158.004992 90)
		(descr "Capacitor SMD 0402")
		(tags "capacitor SMD 0402")
		(property "Reference" "C134"
			(at 0 0.699 270)
			(layer "B.SilkS")
			(hide yes)
			(effects
				(font
					(size 0.7 0.7)
					(thickness 0.15)
				)
				(justify left bottom mirror)
			)
		)
		(property "Value" "C_4u7_0402"
			(at -1.022927 -2.155213 270)
			(layer "B.Fab")
			(effects
				(font
					(size 0.7 0.7)
					(thickness 0.15)
				)
				(justify left bottom mirror)
			)
		)
		(property "Datasheet" "https://www.murata.com/products/productdetail?partno=GRM155R61A475MEAA%23"
			(at 0 0 90)
			(layer "F.Fab")
			(hide yes)
			(effects
				(font
					(size 1.27 1.27)
					(thickness 0.15)
				)
			)
		)
		(property "Author" "Antmicro"
			(at 253.313664 62.69632 0)
			(layer "B.Fab")
			(hide yes)
			(effects
				(font
					(size 1 1)
					(thickness 0.15)
				)
				(justify mirror)
			)
		)
		(property "Dielectric" ""
			(at 253.313664 62.69632 0)
			(layer "B.Fab")
			(hide yes)
			(effects
				(font
					(size 1 1)
					(thickness 0.15)
				)
				(justify mirror)
			)
		)
		(property "License" "Apache-2.0"
			(at 253.313664 62.69632 0)
			(layer "B.Fab")
			(hide yes)
			(effects
				(font
					(size 1 1)
					(thickness 0.15)
				)
				(justify mirror)
			)
		)
		(property "MPN" "GRM155R61A475MEAAD"
			(at 253.313664 62.69632 0)
			(layer "B.Fab")
			(hide yes)
			(effects
				(font
					(size 1 1)
					(thickness 0.15)
				)
				(justify mirror)
			)
		)
		(property "Manufacturer" "Murata"
			(at 253.313664 62.69632 0)
			(layer "B.Fab")
			(hide yes)
			(effects
				(font
					(size 1 1)
					(thickness 0.15)
				)
				(justify mirror)
			)
		)
		(property "Val" "4u7"
			(at 253.313664 62.69632 0)
			(layer "B.Fab")
			(hide yes)
			(effects
				(font
					(size 1 1)
					(thickness 0.15)
				)
				(justify mirror)
			)
		)
		(property "Voltage" ""
			(at 253.313664 62.69632 0)
			(layer "B.Fab")
			(hide yes)
			(effects
				(font
					(size 1 1)
					(thickness 0.15)
				)
				(justify mirror)
			)
		)
		(sheetname "/Ethernet/")
		(sheetfile "ethernet.kicad_sch")
		(attr smd)
		(fp_rect
			(start -0.9659 0.481258)
			(end 0.9649 -0.458742)
			(stroke
				(width 0.05)
				(type solid)
			)
			(fill no)
			(layer "B.CrtYd")
		)
		(fp_line
			(start 0.499 -0.248)
			(end -0.499 -0.248)
			(stroke
				(width 0.15)
				(type solid)
			)
			(layer "B.Fab")
		)
		(fp_line
			(start -0.499 -0.248)
			(end -0.499 0.25)
			(stroke
				(width 0.15)
				(type solid)
			)
			(layer "B.Fab")
		)
		(fp_line
			(start 0.499 0.25)
			(end 0.499 -0.248)
			(stroke
				(width 0.15)
				(type solid)
			)
			(layer "B.Fab")
		)
		(fp_line
			(start -0.499 0.25)
			(end 0.499 0.25)
			(stroke
				(width 0.15)
				(type solid)
			)
			(layer "B.Fab")
		)
		(pad "1" smd roundrect
			(at -0.484 0 90)
			(size 0.59 0.64)
			(layers "B.Cu" "B.Mask" "B.Paste")
			(roundrect_rratio 0.25)
			(net 200 "+3V3")
			(pintype "passive")
		)
		(pad "2" smd roundrect
			(at 0.484 0 90)
			(size 0.59 0.64)
			(layers "B.Cu" "B.Mask" "B.Paste")
			(roundrect_rratio 0.25)
			(net 1 "GND")
			(pintype "passive")
		)
	)
	(footprint "antmicro-footprints:C_0402_1005Metric"
		(layer "B.Cu")
		(at 93.036829 150.283157 90)
		(descr "Capacitor SMD 0402")
		(tags "capacitor SMD 0402")
		(property "Reference" "C143"
			(at 0 0.699 270)
			(layer "B.SilkS")
			(hide yes)
			(effects
				(font
					(size 0.7 0.7)
					(thickness 0.15)
				)
				(justify left bottom mirror)
			)
		)
		(property "Value" "C_470n_0402"
			(at -1.022927 -2.155213 270)
			(layer "B.Fab")
			(effects
				(font
					(size 0.7 0.7)
					(thickness 0.15)
				)
				(justify left bottom mirror)
			)
		)
		(property "Datasheet" "https://product.tdk.com/en/search/capacitor/ceramic/mlcc/info?part_no=C1005X5R1E474M050BB"
			(at 0 0 90)
			(layer "F.Fab")
			(hide yes)
			(effects
				(font
					(size 1.27 1.27)
					(thickness 0.15)
				)
			)
		)
		(property "Author" "Antmicro"
			(at 243.319986 57.246328 0)
			(layer "B.Fab")
			(hide yes)
			(effects
				(font
					(size 1 1)
					(thickness 0.15)
				)
				(justify mirror)
			)
		)
		(property "Dielectric" ""
			(at 243.319986 57.246328 0)
			(layer "B.Fab")
			(hide yes)
			(effects
				(font
					(size 1 1)
					(thickness 0.15)
				)
				(justify mirror)
			)
		)
		(property "License" "Apache-2.0"
			(at 243.319986 57.246328 0)
			(layer "B.Fab")
			(hide yes)
			(effects
				(font
					(size 1 1)
					(thickness 0.15)
				)
				(justify mirror)
			)
		)
		(property "MPN" "C1005X5R1E474M050BB"
			(at 243.319986 57.246328 0)
			(layer "B.Fab")
			(hide yes)
			(effects
				(font
					(size 1 1)
					(thickness 0.15)
				)
				(justify mirror)
			)
		)
		(property "Manufacturer" "TDK"
			(at 243.319986 57.246328 0)
			(layer "B.Fab")
			(hide yes)
			(effects
				(font
					(size 1 1)
					(thickness 0.15)
				)
				(justify mirror)
			)
		)
		(property "Val" "470n"
			(at 243.319986 57.246328 0)
			(layer "B.Fab")
			(hide yes)
			(effects
				(font
					(size 1 1)
					(thickness 0.15)
				)
				(justify mirror)
			)
		)
		(property "Voltage" ""
			(at 243.319986 57.246328 0)
			(layer "B.Fab")
			(hide yes)
			(effects
				(font
					(size 1 1)
					(thickness 0.15)
				)
				(justify mirror)
			)
		)
		(sheetname "/Ethernet/")
		(sheetfile "ethernet.kicad_sch")
		(attr smd)
		(fp_rect
			(start -0.9659 0.481258)
			(end 0.9649 -0.458742)
			(stroke
				(width 0.05)
				(type solid)
			)
			(fill no)
			(layer "B.CrtYd")
		)
		(fp_line
			(start 0.499 -0.248)
			(end -0.499 -0.248)
			(stroke
				(width 0.15)
				(type solid)
			)
			(layer "B.Fab")
		)
		(fp_line
			(start -0.499 -0.248)
			(end -0.499 0.25)
			(stroke
				(width 0.15)
				(type solid)
			)
			(layer "B.Fab")
		)
		(fp_line
			(start 0.499 0.25)
			(end 0.499 -0.248)
			(stroke
				(width 0.15)
				(type solid)
			)
			(layer "B.Fab")
		)
		(fp_line
			(start -0.499 0.25)
			(end 0.499 0.25)
			(stroke
				(width 0.15)
				(type solid)
			)
			(layer "B.Fab")
		)
		(pad "1" smd roundrect
			(at -0.484 0 90)
			(size 0.59 0.64)
			(layers "B.Cu" "B.Mask" "B.Paste")
			(roundrect_rratio 0.25)
			(net 132 "/Ethernet/AVDDL")
			(pintype "passive")
		)
		(pad "2" smd roundrect
			(at 0.484 0 90)
			(size 0.59 0.64)
			(layers "B.Cu" "B.Mask" "B.Paste")
			(roundrect_rratio 0.25)
			(net 1 "GND")
			(pintype "passive")
		)
	)
)
